FILE_TYPE = CONNECTIVITY;
{Allegro Design Entry HDL 17.4-2019 S026 (4007227) 1/17/2022}
"PAGE_NUMBER" = 358;
0"NC";
1"GND\g";
2"GND\g";
3"GND\g";
4"GND\g";
5"GND\g";
6"GND\g";
7"P3V3_AUX\g";
8"GND\g";
9"GND\g";
10"P3V3_AUX\g";
11"GND\g";
12"GND\g";
13"GND\g";
14"GND\g";
15"GND\g";
16"GND\g";
17"GND\g";
18"GND\g";
19"RST_USB_HUB_N";
20"RST_USB_HUB_R_N";
21"USB_HUB_PSELF";
22"GND\g";
23"P3V3_AUX\g";
24"GND\g";
25"P3V3_AUX\g";
26"GND\g";
27"GND\g";
28"P3V3_AUX\g";
29"USB_HUB_PGANG";
30"USB_HUB_PSELF";
31"USB_HUB_RREF";
32"P3V3_AUX_USB_HUB";
33"USB_HUB_DVDD";
34"USB_HUB_OVCUR4";
35"USB2_HUB_SWB_DN";
36"USB2_HUB_SWB_DP";
37"USB2_P0_R_DN";
38"USB2_P0_R_DP";
39"USB_HUB_XTAL_OUT";
40"USB_HUB_XTAL_IN";
41"USB_HUB_TEST";
42"USB2_HOST_BMC_B_DN";
43"USB2_HOST_BMC_B_BUF_DN";
44"USB2_HOST_BMC_B_BUF_DP";
45"USB2_HUB_BUF_SWB_R_DP";
46"USB2_HUB_BUF_SWB_R_DN";
47"TP_USB2_TEST";
48"PD_U5201_VREG";
49"USB2_HUB_BUF_SWB_R_DN";
50"USB2_HUB_BUF_SWB_R_DP";
51"PD_U5201_EQ";
52"USB2_HOST_BMC_B_DP";
53"TP_USB2_CD";
54"PD_U5201_RSTN";
55"TP_USB2_ENA_HS";
56"USB2_HUB_BUF_SWB_DN";
57"USB2_HUB_BUF_SWB_DP";
58"USB2_HUB_SWB_DP";
59"NC_USB_HUB_DM4";
60"NC_USB_HUB_DP2";
61"USB2_HUB_SWB_DN";
62"USB_HUB_OVCUR1";
63"USB_HUB_OVCUR2";
64"USB_HUB_OVCUR3";
65"USB_HUB_OVCUR2";
66"USB_HUB_OVCUR4";
67"USB_HUB_OVCUR1";
68"USB_HUB_OVCUR3";
69"NC_USB_HUB_DM3";
70"NC_USB_HUB_DP4";
71"NC_USB_HUB_DP3";
72"NC_USB_HUB_DM2";
73"NC_USB_HUB_SDA";
%"GL852GOHY60"
"1","(125,3825)","0","pure_quanta","I100";
;
LOCATION"U268"
$SEC"1"
CDS_SEC"1"
VALUE"GL852G-OHY60"
MATERIAL"IC"
PART_TYPE"SMLF"
ROOM"USB2 BOM1"
CDS_LIB"pure_quanta"
CDS_LMAN_SYM_OUTLINE"-325,600,325,-600"
NEEDS_NO_SIZE"TRUE"
PART_NUMBER"AL000852001";
"DM4"
$PN"15"59;
"DP4"
$PN"16"70;
"DM3"
$PN"12"69;
"DP3"
$PN"13"71;
"DM2"
$PN"6"72;
"DP2"
$PN"7"60;
"DM1"
$PN"3"35;
"DP1"
$PN"4"36;
"DM0"
$PN"1"37;
"DP0"
$PN"2"38;
"RREF"
$PN"8"31;
"PSELF"
$PN"22"30;
"PGANG"
$PN"23"29;
"RESET# \B"
$PN"17"20;
"OVCUR4# \B"
$PN"19"34;
"OVCUR3# \B"
$PN"20"68;
"OVCUR2#||SMD"
$PN"24"65;
"OVCUR1#||SMC"
$PN"25"67;
"TH"
$PN"TH"8;
"DVDD"
$PN"21"33;
"AVDD<2>"
$PN"14"32;
"AVDD<1>"
$PN"9"32;
"AVDD<0>"
$PN"5"32;
"V33"
$PN"28"32;
"V5"
$PN"27"32;
"SDA"
$PN"26"73;
"TEST||SCL"
$PN"18"41;
"X2"
$PN"11"39;
"X1"
$PN"10"40;
%"UNIVERSAL_GND"
"1","(3700,4325)","0","pure_quanta_power","I115";
;
CDS_LIB"pure_quanta_power"
HDL_POWER"GND";
"A"1;
%"UNIVERSAL_GND"
"1","(4350,4325)","0","pure_quanta_power","I116";
;
CDS_LIB"pure_quanta_power"
HDL_POWER"GND";
"A"2;
%"UNIVERSAL_GND"
"1","(4475,4150)","0","pure_quanta_power","I117";
;
CDS_LIB"pure_quanta_power"
HDL_POWER"GND";
"A"3;
%"UNIVERSAL_GND"
"1","(3475,4150)","0","pure_quanta_power","I118";
;
CDS_LIB"pure_quanta_power"
HDL_POWER"GND";
"A"4;
%"UNIVERSAL_GND"
"1","(2025,4275)","1","pure_quanta_power","I122";
;
CDS_LIB"pure_quanta_power"
HDL_POWER"GND";
"A"5;
%"Q_RES"
"1","(2550,3875)","0","pure_quanta","I137";
;
LOCATION"R3652"
$SEC"1"
CDS_SEC"1"
MATERIAL"CHIP"
PACK_TYPE"0402LF"
ROOM"USB2 BOM1"
VALUE"0"
TOLERANCE"5%"
WATTAGE"1/16W"
CDS_LIB"pure_quanta"
PART_NUMBER"CS00002JB13";
"B"
$PN"2"42;
"A"
$PN"1"37;
%"Q_RES"
"1","(2550,3925)","0","pure_quanta","I138";
;
LOCATION"R3651"
$SEC"1"
CDS_SEC"1"
PACK_TYPE"0402LF"
ROOM"USB2 BOM1"
VALUE"0"
MATERIAL"CHIP"
WATTAGE"1/16W"
TOLERANCE"5%"
CDS_LIB"pure_quanta"
PART_NUMBER"CS00002JB13";
"B"
$PN"2"52;
"A"
$PN"1"38;
%"Q_RES"
"2","(-1075,3100)","0","pure_quanta","I139";
;
LOCATION"R3653"
$SEC"1"
CDS_SEC"1"
WATTAGE"1/16W"
ROOM"USB2 BOM1"
PACK_TYPE"0402LF"
MATERIAL"CHIP"
TOLERANCE"1%"
VALUE"680"
CDS_LIB"pure_quanta"
PART_NUMBER"CS16802FB03";
"A"
$PN"1"31;
"B"
$PN"2"6;
%"UNIVERSAL_GND"
"1","(-1075,2825)","0","pure_quanta_power","I140";
;
CDS_LIB"pure_quanta_power"
HDL_POWER"GND";
"A"6;
%"Q_CAP"
"1","(-1175,4500)","2","pure_quanta","I142";
;
LOCATION"C2034"
$SEC"1"
CDS_SEC"1"
ROOM"USB2 BOM1"
VOLTAGE"25V"
VALUE"0.1UF"
MATERIAL"X7R"
TOLERANCE"10%"
PACK_TYPE"0402"
CDS_LIB"pure_quanta"
PART_NUMBER"CH4104K1B00";
"B"
$PN"2"22;
"A"
$PN"1"32;
%"Q_CAP"
"1","(-1550,4500)","2","pure_quanta","I143";
;
LOCATION"C2033"
$SEC"1"
CDS_SEC"1"
ROOM"USB2 BOM1"
PACK_TYPE"0402"
VALUE"0.1UF"
TOLERANCE"10%"
MATERIAL"X7R"
VOLTAGE"25V"
CDS_LIB"pure_quanta"
PART_NUMBER"CH4104K1B00";
"B"
$PN"2"22;
"A"
$PN"1"32;
%"UNIVERSAL_POWER"
"1","(-4000,4950)","2","pure_quanta_power","I144";
;
HDL_POWER"P3V3_AUX"
CDS_LIB"pure_quanta_power";
"A"23;
%"Q_CAP"
"1","(-1925,4500)","2","pure_quanta","I145";
;
LOCATION"C2032"
$SEC"1"
CDS_SEC"1"
ROOM"USB2 BOM1"
PACK_TYPE"0402"
MATERIAL"X7R"
TOLERANCE"10%"
VOLTAGE"25V"
VALUE"0.1UF"
CDS_LIB"pure_quanta"
PART_NUMBER"CH4104K1B00";
"B"
$PN"2"22;
"A"
$PN"1"32;
%"Q_CAP"
"1","(-825,4500)","0","pure_quanta","I147";
;
LOCATION"C2035"
$SEC"1"
CDS_SEC"1"
ROOM"USB2 BOM1"
VALUE"1UF"
MATERIAL"X6S"
VOLTAGE"25V"
TOLERANCE"10%"
PACK_TYPE"C0402"
CDS_LIB"pure_quanta"
PART_NUMBER"CH5104KEB02";
"B"
$PN"2"22;
"A"
$PN"1"32;
%"Q_CAP"
"1","(-2300,4500)","0","pure_quanta","I148";
;
LOCATION"C2031"
$SEC"1"
CDS_SEC"1"
ROOM"USB2 BOM1"
TOLERANCE"10%"
PACK_TYPE"C0402"
VALUE"1UF"
VOLTAGE"25V"
MATERIAL"X6S"
CDS_LIB"pure_quanta"
PART_NUMBER"CH5104KEB02";
"B"
$PN"2"22;
"A"
$PN"1"32;
%"UNIVERSAL_POWER"
"1","(-1900,4075)","2","pure_quanta_power","I151";
;
HDL_POWER"P3V3_AUX"
CDS_LIB"pure_quanta_power";
"A"7;
%"Q_RES"
"1","(-2725,3425)","0","pure_quanta","I155";
;
LOCATION"R3654"
$SEC"1"
CDS_SEC"1"
VALUE"33.2"
MATERIAL"CHIP"
TOLERANCE"1%"
WATTAGE"1/16W"
PACK_TYPE"0402LF"
CDS_LIB"pure_quanta"
PART_NUMBER"CS03322FB03";
"B"
$PN"2"20;
"A"
$PN"1"19;
%"UNIVERSAL_GND"
"1","(-2275,2850)","0","pure_quanta_power","I157";
;
CDS_LIB"pure_quanta_power"
HDL_POWER"GND";
"A"24;
%"Q_CAP"
"1","(-2275,3150)","0","pure_quanta","I158";
;
LOCATION"C2041"
$SEC"1"
CDS_SEC"1"
VALUE"1UF"
MATERIAL"X6S"
PACK_TYPE"C0402"
TOLERANCE"10%"
VOLTAGE"25V"
CDS_LIB"pure_quanta"
PART_NUMBER"CH5104KEB02";
"B"
$PN"2"24;
"A"
$PN"1"20;
%"Q_RES"
"2","(-1900,3775)","0","pure_quanta","I159";
;
LOCATION"R3660"
$SEC"1"
CDS_SEC"1"
TOLERANCE"1%"
WATTAGE"1/16W"
VALUE"10K"
PACK_TYPE"0402LF"
MATERIAL"CHIP"
CDS_LIB"pure_quanta"
PART_NUMBER"CS31002FB08";
"A"
$PN"1"7;
"B"
$PN"2"20;
%"Q_RES"
"1","(-3750,4800)","0","pure_quanta","I161";
;
LOCATION"R3655"
$SEC"1"
CDS_SEC"1"
ROOM"USB2 BOM1"
PACK_TYPE"0402LF"
MATERIAL"CHIP"
VALUE"0"
CDS_LIB"pure_quanta"
WATTAGE"1/16W"
TOLERANCE"5%"
PART_NUMBER"CS00002JB13";
"B"
$PN"2"32;
"A"
$PN"1"23;
%"Q_CAP"
"1","(-2675,4500)","2","pure_quanta","I162";
;
LOCATION"C2040"
$SEC"1"
CDS_SEC"1"
ROOM"USB2 BOM1"
MATERIAL"X7R"
PACK_TYPE"0402"
TOLERANCE"10%"
VOLTAGE"25V"
VALUE"0.1UF"
CDS_LIB"pure_quanta"
PART_NUMBER"CH4104K1B00";
"B"
$PN"2"22;
"A"
$PN"1"32;
%"Q_CAP"
"1","(-3075,4500)","2","pure_quanta","I163";
;
LOCATION"C2039"
$SEC"1"
CDS_SEC"1"
ROOM"USB2 BOM1"
TOLERANCE"10%"
VOLTAGE"25V"
MATERIAL"X7R"
PACK_TYPE"0402"
VALUE"0.1UF"
CDS_LIB"pure_quanta"
PART_NUMBER"CH4104K1B00";
"B"
$PN"2"22;
"A"
$PN"1"32;
%"Q_CAP"
"1","(-3450,4500)","0","pure_quanta","I164";
;
LOCATION"C2038"
$SEC"1"
CDS_SEC"1"
ROOM"USB2 BOM1"
TOLERANCE"20%"
VOLTAGE"6.3V"
MATERIAL"X6S"
VALUE"10UF"
PACK_TYPE"C0402"
CDS_LIB"pure_quanta"
PART_NUMBER"CH6101MEB01";
"B"
$PN"2"22;
"A"
$PN"1"32;
%"UNIVERSAL_GND"
"1","(-3450,4100)","0","pure_quanta_power","I165";
;
CDS_LIB"pure_quanta_power"
HDL_POWER"GND";
"A"22;
%"UNIVERSAL_GND"
"1","(725,3125)","0","pure_quanta_power","I166";
;
CDS_LIB"pure_quanta_power"
HDL_POWER"GND";
"A"8;
%"Q_RES"
"1","(-1025,3925)","0","pure_quanta","I167";
;
LOCATION"R3662"
$SEC"1"
CDS_SEC"1"
MATERIAL"CHIP"
PACK_TYPE"0402LF"
VALUE"0"
ROOM"USB2 BOM1"
WATTAGE"1/16W"
TOLERANCE"5%"
CDS_LIB"pure_quanta"
PART_NUMBER"CS00002JB13";
"B"
$PN"2"33;
"A"
$PN"1"32;
%"Q_RES"
"2","(-750,3075)","0","pure_quanta","I182";
;
LOCATION"R3665"
$SEC"1"
CDS_SEC"1"
ROOM"USB2 BOM1"
PACK_TYPE"0402LF"
MATERIAL"CHIP"
WATTAGE"1/16W"
TOLERANCE"1%"
VALUE"100K"
CDS_LIB"pure_quanta"
PART_NUMBER"CS41002FB09";
"A"
$PN"1"29;
"B"
$PN"2"9;
%"UNIVERSAL_GND"
"1","(-750,2800)","0","pure_quanta_power","I183";
;
CDS_LIB"pure_quanta_power"
HDL_POWER"GND";
"A"9;
%"UNIVERSAL_POWER"
"1","(-4150,3400)","2","pure_quanta_power","I185";
;
HDL_POWER"P3V3_AUX"
CDS_LIB"pure_quanta_power";
"A"10;
%"Q_RES"
"2","(-4150,2950)","0","pure_quanta","I186";
;
LOCATION"R3663"
$SEC"1"
CDS_SEC"1"
PACK_TYPE"0402LF"
VALUE"10K"
TOLERANCE"1%"
WATTAGE"1/16W"
MATERIAL"CHIP"
ROOM"USB2 BOM1"
CDS_LIB"pure_quanta"
PART_NUMBER"CS31002FB08";
"A"
$PN"1"10;
"B"
$PN"2"21;
%"Q_RES"
"2","(-4150,2350)","0","pure_quanta","I187";
;
LOCATION"R3664"
$SEC"1"
CDS_SEC"1"
PACK_TYPE"0402LF"
VALUE"10K"
TOLERANCE"1%"
MATERIAL"EMPTY"
WATTAGE"1/16W"
ROOM"USB2 BOM1"
CDS_LIB"pure_quanta"
PART_NUMBER"CS31002FB08";
"A"
$PN"1"21;
"B"
$PN"2"11;
%"UNIVERSAL_GND"
"1","(-4150,1925)","0","pure_quanta_power","I188";
;
CDS_LIB"pure_quanta_power"
HDL_POWER"GND";
"A"11;
%"Q_RES"
"1","(-1550,2275)","0","pure_quanta","I194";
;
LOCATION"R3656"
$SEC"1"
CDS_SEC"1"
ROOM"USB2 BOM1"
MATERIAL"EMPTY"
VALUE"10K"
CDS_LIB"pure_quanta"
PACK_TYPE"0402LF"
TOLERANCE"1%"
WATTAGE"1/16W"
PART_NUMBER"CS31002FB08";
"B"
$PN"2"62;
"A"
$PN"1"25;
%"Q_RES"
"1","(-1550,2125)","0","pure_quanta","I195";
;
LOCATION"R3657"
$SEC"1"
CDS_SEC"1"
MATERIAL"EMPTY"
VALUE"10K"
ROOM"USB2 BOM1"
CDS_LIB"pure_quanta"
WATTAGE"1/16W"
TOLERANCE"1%"
PACK_TYPE"0402LF"
PART_NUMBER"CS31002FB08";
"B"
$PN"2"63;
"A"
$PN"1"25;
%"Q_RES"
"1","(-1550,2000)","0","pure_quanta","I196";
;
LOCATION"R3658"
$SEC"1"
CDS_SEC"1"
VALUE"10K"
ROOM"USB2 BOM1"
MATERIAL"EMPTY"
CDS_LIB"pure_quanta"
PACK_TYPE"0402LF"
TOLERANCE"1%"
WATTAGE"1/16W"
PART_NUMBER"CS31002FB08";
"B"
$PN"2"64;
"A"
$PN"1"25;
%"UNIVERSAL_POWER"
"1","(-2175,2525)","2","pure_quanta_power","I197";
;
HDL_POWER"P3V3_AUX"
CDS_LIB"pure_quanta_power";
"A"25;
%"Q_RES"
"1","(-1550,1875)","0","pure_quanta","I198";
;
LOCATION"R3659"
$SEC"1"
CDS_SEC"1"
ROOM"USB2 BOM1"
VALUE"10K"
WATTAGE"1/16W"
TOLERANCE"1%"
MATERIAL"EMPTY"
PACK_TYPE"0402LF"
CDS_LIB"pure_quanta"
PART_NUMBER"CS31002FB08";
"B"
$PN"2"66;
"A"
$PN"1"25;
%"Q_RES"
"1","(1375,4275)","0","pure_quanta","I199";
;
LOCATION"R3666"
$SEC"1"
CDS_SEC"1"
PACK_TYPE"0402LF"
MATERIAL"CHIP"
ROOM"USB2 BOM1"
VALUE"0"
WATTAGE"1/16W"
TOLERANCE"5%"
CDS_LIB"pure_quanta"
PART_NUMBER"CS00002JB13";
"B"
$PN"2"5;
"A"
$PN"1"41;
%"Q_RES"
"1","(-1900,3100)","1","pure_quanta","I201";
;
LOCATION"R3661"
$SEC"1"
CDS_SEC"1"
PACK_TYPE"0402LF"
WATTAGE"1/16W"
MATERIAL"EMPTY"
VALUE"47K"
TOLERANCE"0.1%"
CDS_LIB"pure_quanta"
PART_NUMBER"CS34702BB05";
"B"
$PN"2"20;
"A"
$PN"1"24;
%"Q_RES"
"2","(3625,3675)","0","pure_quanta","I202";
;
LOCATION"R4420"
$SEC"1"
CDS_SEC"1"
MATERIAL"EMPTY"
VALUE"49.9"
PACK_TYPE"0402LF"
TOLERANCE"1%"
WATTAGE"1/16W"
CDS_LIB"pure_quanta"
PART_NUMBER"CS04992FB07";
"A"
$PN"1"42;
"B"
$PN"2"12;
%"Q_RES"
"2","(3450,3675)","0","pure_quanta","I203";
;
LOCATION"R4419"
$SEC"1"
CDS_SEC"1"
MATERIAL"EMPTY"
VALUE"49.9"
WATTAGE"1/16W"
TOLERANCE"1%"
PACK_TYPE"0402LF"
CDS_LIB"pure_quanta"
PART_NUMBER"CS04992FB07";
"A"
$PN"1"52;
"B"
$PN"2"13;
%"UNIVERSAL_GND"
"1","(3625,3450)","0","pure_quanta_power","I204";
;
CDS_LIB"pure_quanta_power"
HDL_POWER"GND";
"A"12;
%"UNIVERSAL_GND"
"1","(3450,3450)","0","pure_quanta_power","I205";
;
CDS_LIB"pure_quanta_power"
HDL_POWER"GND";
"A"13;
%"Q_RES"
"2","(-2275,1025)","0","pure_quanta","I206";
;
LOCATION"R4483"
$SEC"1"
CDS_SEC"1"
VALUE"49.9"
MATERIAL"EMPTY"
PACK_TYPE"0402LF"
TOLERANCE"1%"
WATTAGE"1/16W"
CDS_LIB"pure_quanta"
PART_NUMBER"CS04992FB07";
"A"
$PN"1"43;
"B"
$PN"2"14;
%"UNIVERSAL_GND"
"1","(-2275,800)","0","pure_quanta_power","I207";
;
CDS_LIB"pure_quanta_power"
HDL_POWER"GND";
"A"14;
%"Q_RES"
"2","(-2450,1025)","0","pure_quanta","I208";
;
LOCATION"R4482"
$SEC"1"
CDS_SEC"1"
VALUE"49.9"
MATERIAL"EMPTY"
WATTAGE"1/16W"
TOLERANCE"1%"
PACK_TYPE"0402LF"
CDS_LIB"pure_quanta"
PART_NUMBER"CS04992FB07";
"A"
$PN"1"44;
"B"
$PN"2"15;
%"UNIVERSAL_GND"
"1","(-2450,800)","0","pure_quanta_power","I209";
;
CDS_LIB"pure_quanta_power"
HDL_POWER"GND";
"A"15;
%"Q_XTAL_4P_13BI_24GND"
"1","(4025,4550)","0","pure_quanta","I210";
;
LOCATION"Y8004"
SEC"1"
MATERIAL"MISC"
ROOM"USB2 BOM1"
VALUE"12MHZ"
PART_TYPE"SMLF"
SEC_TYPE""
CDS_LIB"pure_quanta"
PIN_NAMES_ROTATE"True"
CDS_LMAN_SYM_OUTLINE"-125,175,125,-175"
PART_NUMBER"BG6120000B0";
"X2"
$PN"3"39;
"G2"
$PN"4"2;
"G1"
$PN"2"1;
"X1"
$PN"1"40;
%"Q_CAP"
"1","(4475,4375)","0","pure_quanta","I211";
;
LOCATION"C2030"
$SEC"1"
CDS_SEC"1"
VOLTAGE"50V"
TOLERANCE"5%"
PACK_TYPE"0402"
MATERIAL"C0G"
VALUE"15PF"
ROOM"USB2 BOM1"
CDS_LIB"pure_quanta"
PART_NUMBER"CH01506JB06";
"B"
$PN"2"3;
"A"
$PN"1"39;
%"Q_CAP"
"1","(3475,4375)","0","pure_quanta","I212";
;
LOCATION"C2029"
$SEC"1"
CDS_SEC"1"
ROOM"USB2 BOM1"
MATERIAL"C0G"
PACK_TYPE"0402"
VALUE"15PF"
VOLTAGE"50V"
TOLERANCE"5%"
CDS_LIB"pure_quanta"
PART_NUMBER"CH01506JB06";
"B"
$PN"2"4;
"A"
$PN"1"40;
%"Q_RES"
"1","(-2175,175)","0","pure_quanta","I78";
;
LOCATION"R2787"
$SEC"1"
CDS_SEC"1"
VALUE"0"
MATERIAL"CHIP"
PACK_TYPE"0402LF"
ROOM"USB2 BOM1"
CDS_LIB"pure_quanta"
WATTAGE"1/16W"
TOLERANCE"5%"
PART_NUMBER"CS00002JB13";
"B"
$PN"2"46;
"A"
$PN"1"61;
%"Q_RES"
"1","(-2175,225)","0","pure_quanta","I79";
;
LOCATION"R2786"
$SEC"1"
CDS_SEC"1"
ROOM"USB2 BOM1"
VALUE"0"
MATERIAL"CHIP"
PACK_TYPE"0402LF"
CDS_LIB"pure_quanta"
WATTAGE"1/16W"
TOLERANCE"5%"
PART_NUMBER"CS00002JB13";
"B"
$PN"2"45;
"A"
$PN"1"58;
%"UNIVERSAL_GND"
"1","(-1150,-450)","0","pure_quanta_power","I80";
;
CDS_LIB"pure_quanta_power"
HDL_POWER"GND";
"A"16;
%"Q_CAP"
"1","(-1150,-225)","0","pure_quanta","I81";
;
LOCATION"C5232"
$SEC"1"
CDS_SEC"1"
ROOM"USB2 BOM2"
PACK_TYPE"C0402"
VALUE"0.1UF"
VOLTAGE"25V"
TOLERANCE"10%"
MATERIAL"EMPTY"
CDS_LIB"pure_quanta"
PART_NUMBER"CH4104KEB00";
"B"
$PN"2"16;
"A"
$PN"1"54;
%"UNIVERSAL_GND"
"1","(-675,-450)","0","pure_quanta_power","I82";
;
CDS_LIB"pure_quanta_power"
HDL_POWER"GND";
"A"17;
%"Q_RES"
"2","(-675,-250)","0","pure_quanta","I83";
;
LOCATION"R5238"
$SEC"1"
CDS_SEC"1"
ROOM"USB2 BOM2"
WATTAGE"1/16W"
VALUE"3.9K"
MATERIAL"EMPTY"
TOLERANCE"5%"
PACK_TYPE"0402LF"
CDS_LIB"pure_quanta"
PART_NUMBER"CS23902JB04";
"A"
$PN"1"51;
"B"
$PN"2"17;
%"TUSB211IRWBR"
"1","(-125,100)","0","pure_quanta","I84";
;
LOCATION"U5201"
$SEC"1"
CDS_SEC"1"
MATERIAL"EMPTY"
VALUE"TUSB211IRWBR"
PART_TYPE"SMLF"
ROOM"USB2 BOM2"
CDS_LIB"pure_quanta"
CDS_LMAN_SYM_OUTLINE"-225,175,225,-175"
NEEDS_NO_SIZE"TRUE"
PART_NUMBER"AL000211007";
"GND"
$PN"10"26;
"EQ"
$PN"6"51;
"D2P"
$PN"7"50;
"D1P"
$PN"2"45;
"D1M"
$PN"1"46;
"CD"
$PN"4"53;
"ENA_HS"
$PN"9"55;
"VCC"
$PN"12"28;
"TEST"
$PN"3"47;
"VREG"
$PN"11"48;
"D2M"
$PN"8"49;
"RSTN"
$PN"5"54;
%"UNIVERSAL_GND"
"1","(1475,-425)","0","pure_quanta_power","I85";
;
CDS_LIB"pure_quanta_power"
HDL_POWER"GND";
"A"18;
%"UNIVERSAL_GND"
"1","(1375,-150)","0","pure_quanta_power","I86";
;
CDS_LIB"pure_quanta_power"
HDL_POWER"GND";
"A"26;
%"Q_CAP"
"1","(1475,-200)","0","pure_quanta","I87";
;
LOCATION"C5236"
$SEC"1"
CDS_SEC"1"
ROOM"USB2 BOM2"
VALUE"0.1UF"
VOLTAGE"25V"
PACK_TYPE"C0402"
MATERIAL"EMPTY"
TOLERANCE"10%"
CDS_LIB"pure_quanta"
PART_NUMBER"CH4104KEB00";
"B"
$PN"2"18;
"A"
$PN"1"48;
%"Q_CAP"
"1","(75,700)","0","pure_quanta","I88";
;
LOCATION"C5229"
$SEC"1"
CDS_SEC"1"
ROOM"USB2 BOM2"
MATERIAL"EMPTY"
PACK_TYPE"C0402"
TOLERANCE"10%"
VOLTAGE"25V"
VALUE"1UF"
CDS_LIB"pure_quanta"
PART_NUMBER"CH5104KEB02";
"B"
$PN"2"27;
"A"
$PN"1"28;
%"UNIVERSAL_GND"
"1","(575,375)","0","pure_quanta_power","I89";
;
CDS_LIB"pure_quanta_power"
HDL_POWER"GND";
"A"27;
%"Q_RES"
"1","(1375,175)","0","pure_quanta","I90";
;
LOCATION"R5236"
$SEC"1"
CDS_SEC"1"
VALUE"0"
PACK_TYPE"0402LF"
MATERIAL"CHIP"
CDS_LIB"pure_quanta"
TOLERANCE"5%"
WATTAGE"1/16W"
PART_NUMBER"CS00002JB13";
"B"
$PN"2"56;
"A"
$PN"1"49;
%"Q_RES"
"1","(1375,225)","0","pure_quanta","I91";
;
LOCATION"R5234"
$SEC"1"
CDS_SEC"1"
PACK_TYPE"0402LF"
MATERIAL"CHIP"
VALUE"0"
CDS_LIB"pure_quanta"
TOLERANCE"5%"
WATTAGE"1/16W"
PART_NUMBER"CS00002JB13";
"B"
$PN"2"57;
"A"
$PN"1"50;
%"Q_CAP"
"1","(575,675)","0","pure_quanta","I92";
;
LOCATION"C5234"
$SEC"1"
CDS_SEC"1"
PACK_TYPE"C0402"
MATERIAL"EMPTY"
VALUE"0.1UF"
ROOM"USB2 BOM2"
TOLERANCE"10%"
VOLTAGE"25V"
CDS_LIB"pure_quanta"
PART_NUMBER"CH4104KEB00";
"B"
$PN"2"27;
"A"
$PN"1"28;
%"UNIVERSAL_POWER"
"1","(1125,1050)","2","pure_quanta_power","I95";
;
HDL_POWER"P3V3_AUX"
CDS_LIB"pure_quanta_power";
"A"28;
%"Q_RES"
"2","(2725,3650)","0","pure_quanta","I96";
;
LOCATION"R2790"
$SEC"1"
CDS_SEC"1"
VALUE"0"
MATERIAL"EMPTY"
ROOM"USB2 BOM2"
WATTAGE"1/16W"
TOLERANCE"5%"
PACK_TYPE"0402LF"
CDS_LIB"pure_quanta"
PART_NUMBER"CS00002JB13";
"A"
$PN"1"52;
"B"
$PN"2"44;
%"Q_RES"
"2","(2825,3650)","0","pure_quanta","I97";
;
LOCATION"R2791"
$SEC"1"
CDS_SEC"1"
ROOM"USB2 BOM2"
VALUE"0"
WATTAGE"1/16W"
TOLERANCE"5%"
MATERIAL"EMPTY"
PACK_TYPE"0402LF"
CDS_LIB"pure_quanta"
PART_NUMBER"CS00002JB13";
"A"
$PN"1"42;
"B"
$PN"2"43;
%"Q_RES"
"2","(-1950,375)","0","pure_quanta","I98";
;
LOCATION"R2789"
$SEC"1"
CDS_SEC"1"
MATERIAL"EMPTY"
ROOM"USB2 BOM2"
VALUE"0"
CDS_LIB"pure_quanta"
PACK_TYPE"0402LF"
TOLERANCE"5%"
WATTAGE"1/16W"
PART_NUMBER"CS00002JB13";
"A"
$PN"1"43;
"B"
$PN"2"46;
%"Q_RES"
"2","(-2025,375)","0","pure_quanta","I99";
;
LOCATION"R2788"
$SEC"1"
CDS_SEC"1"
MATERIAL"EMPTY"
ROOM"USB2 BOM2"
PACK_TYPE"0402LF"
VALUE"0"
TOLERANCE"5%"
WATTAGE"1/16W"
CDS_LIB"pure_quanta"
PART_NUMBER"CS00002JB13";
"A"
$PN"1"44;
"B"
$PN"2"45;
END.
